# SCM (Grand Teton) — schematic netlist excerpt (pin names and nets, part order shuffled) for the footprints in the layout excerpt that follows; sources: Cadence DE-HDL packaged netlist, KiCad conversion of 12092022_DA0F0TMDCD0_F0T_Management_Board_D_brd_V3_OCP.brd

C292  Q_CAP  1UF 25V 10% X6S  pkg C0402  page 54 : A = P5V_AUX ; B = GND
L28  Q_INDUCTOR  BLM18BB470/500MA IND  pkg SMLF  page 23 : \1\ = V_DACB ; \2\ = V_DACB_IO

(kicad_pcb
	(version 20260206)
	(generator "pcbnew")
	(generator_version "10.0")
	(general
		(thickness 1.6)
		(legacy_teardrops no)
	)
	(paper "A4")
	(title_block
		(title "12092022_DA0F0TMDCD0_F0T_Management_Board_D_brd_V3_OCP.brd")
		(comment 1 "Grand Teton / footprints 381-382 of 1440")
	)
	(layers
		(0 "F.Cu" signal "TOP")
		(4 "In1.Cu" signal "GND")
		(6 "In2.Cu" signal "IN1")
		(8 "In3.Cu" signal "GND1")
		(10 "In4.Cu" signal "IN2")
		(12 "In5.Cu" signal "VCC")
		(14 "In6.Cu" signal "VCC1")
		(16 "In7.Cu" signal "IN3")
		(18 "In8.Cu" signal "GND2")
		(20 "In9.Cu" signal "IN4")
		(22 "In10.Cu" signal "GND3")
		(2 "B.Cu" signal "BOTTOM")
		(9 "F.Adhes" user "F.Adhesive")
		(11 "B.Adhes" user "B.Adhesive")
		(13 "F.Paste" user "Package Geometry/Pastemask Top")
		(15 "B.Paste" user "Package Geometry/Pastemask Bottom")
		(5 "F.SilkS" user "Ref Des/Silkscreen Top")
		(7 "B.SilkS" user "Ref Des/Silkscreen Bottom")
		(1 "F.Mask" user "Board Geometry/Soldermask Top")
		(3 "B.Mask" user "Board Geometry/Soldermask Bottom")
		(17 "Dwgs.User" user "User.Drawings")
		(19 "Cmts.User" user "User.Comments")
		(21 "Eco1.User" user "User.Eco1")
		(23 "Eco2.User" user "User.Eco2")
		(25 "Edge.Cuts" user "Board Geometry/Outline")
		(27 "Margin" user)
		(31 "F.CrtYd" user "Package Geometry/Place Bound Top")
		(29 "B.CrtYd" user "Package Geometry/Place Bound Bottom")
		(35 "F.Fab" user "Ref Des/Assembly Top")
		(33 "B.Fab" user "Ref Des/Assembly Bottom")
	)
	(footprint ""
		(layer "F.Cu")
		(at 29.2608 -28.5242)
		(property "Reference" "L28"
			(at 0 0 0)
			(layer "F.SilkS")
			(hide yes)
			(effects
				(font
					(size 1.27 1.27)
				)
			)
		)
		(property "Value" ""
			(at 0 0 0)
			(layer "F.Fab")
			(effects
				(font
					(size 1.27 1.27)
				)
			)
		)
		(duplicate_pad_numbers_are_jumpers no)
		(fp_line
			(start -1.27 -0.5842)
			(end 1.27 -0.5842)
			(stroke
				(width 0.1524)
				(type default)
			)
			(layer "F.SilkS")
		)
		(fp_line
			(start -1.27 -0.5588)
			(end -1.27 -0.5842)
			(stroke
				(width 0.1524)
				(type default)
			)
			(layer "F.SilkS")
		)
		(fp_line
			(start -1.27 0.5842)
			(end -1.27 -0.5842)
			(stroke
				(width 0.1524)
				(type default)
			)
			(layer "F.SilkS")
		)
		(fp_line
			(start -0.127 0.5842)
			(end -0.127 -0.5842)
			(stroke
				(width 0.1524)
				(type default)
			)
			(layer "F.SilkS")
		)
		(fp_line
			(start 0.127 0.5842)
			(end 0.127 -0.5842)
			(stroke
				(width 0.1524)
				(type default)
			)
			(layer "F.SilkS")
		)
		(fp_line
			(start 1.27 0.5842)
			(end -1.27 0.5842)
			(stroke
				(width 0.1524)
				(type default)
			)
			(layer "F.SilkS")
		)
		(fp_line
			(start 1.27 0.5842)
			(end 1.27 -0.5842)
			(stroke
				(width 0.1524)
				(type default)
			)
			(layer "F.SilkS")
		)
		(fp_line
			(start -1.194308 -0.406654)
			(end -0.9144 -0.406654)
			(stroke
				(width 0.1)
				(type default)
			)
			(layer "F.Fab")
		)
		(fp_line
			(start -1.194308 0.406654)
			(end -1.194308 -0.406654)
			(stroke
				(width 0.1)
				(type default)
			)
			(layer "F.Fab")
		)
		(fp_line
			(start -0.9144 -0.508)
			(end 0.9144 -0.508)
			(stroke
				(width 0.1)
				(type default)
			)
			(layer "F.Fab")
		)
		(fp_line
			(start -0.9144 -0.406654)
			(end -0.9144 -0.508)
			(stroke
				(width 0.1)
				(type default)
			)
			(layer "F.Fab")
		)
		(fp_line
			(start -0.9144 0.406654)
			(end -1.194308 0.406654)
			(stroke
				(width 0.1)
				(type default)
			)
			(layer "F.Fab")
		)
		(fp_line
			(start -0.9144 0.508)
			(end -0.9144 0.406654)
			(stroke
				(width 0.1)
				(type default)
			)
			(layer "F.Fab")
		)
		(fp_line
			(start 0.9144 -0.508)
			(end 0.9144 -0.406654)
			(stroke
				(width 0.1)
				(type default)
			)
			(layer "F.Fab")
		)
		(fp_line
			(start 0.9144 -0.406654)
			(end 1.1938 -0.406654)
			(stroke
				(width 0.1)
				(type default)
			)
			(layer "F.Fab")
		)
		(fp_line
			(start 0.9144 0.4064)
			(end 0.9144 0.508)
			(stroke
				(width 0.1)
				(type default)
			)
			(layer "F.Fab")
		)
		(fp_line
			(start 0.9144 0.508)
			(end -0.9144 0.508)
			(stroke
				(width 0.1)
				(type default)
			)
			(layer "F.Fab")
		)
		(fp_line
			(start 1.1938 -0.406654)
			(end 1.1938 0.4064)
			(stroke
				(width 0.1)
				(type default)
			)
			(layer "F.Fab")
		)
		(fp_line
			(start 1.1938 0.4064)
			(end 0.9144 0.4064)
			(stroke
				(width 0.1)
				(type default)
			)
			(layer "F.Fab")
		)
		(pad "1" smd rect
			(at -0.7366 0 270)
			(size 0.7112 0.8128)
			(layers "F.Cu" "F.Mask" "F.Paste")
			(net "V_DACB")
		)
		(pad "2" smd rect
			(at 0.7366 0 270)
			(size 0.7112 0.8128)
			(layers "F.Cu" "F.Mask" "F.Paste")
			(net "V_DACB_IO")
		)
	)
	(footprint ""
		(layer "F.Cu")
		(at 35.052 -53.213 -90)
		(property "Reference" "C292"
			(at 0 0 270)
			(layer "F.SilkS")
			(hide yes)
			(effects
				(font
					(size 1.27 1.27)
				)
			)
		)
		(property "Value" ""
			(at 0 0 270)
			(layer "F.Fab")
			(effects
				(font
					(size 1.27 1.27)
				)
			)
		)
		(duplicate_pad_numbers_are_jumpers no)
		(fp_line
			(start -0.7874 0.4064)
			(end -0.7874 -0.4064)
			(stroke
				(width 0.1524)
				(type default)
			)
			(layer "F.SilkS")
		)
		(fp_line
			(start 0.7874 0.4064)
			(end -0.7874 0.4064)
			(stroke
				(width 0.1524)
				(type default)
			)
			(layer "F.SilkS")
		)
		(fp_line
			(start -0.7874 -0.4064)
			(end 0.7874 -0.4064)
			(stroke
				(width 0.1524)
				(type default)
			)
			(layer "F.SilkS")
		)
		(fp_line
			(start 0.7874 -0.4064)
			(end 0.7874 0.4064)
			(stroke
				(width 0.1524)
				(type default)
			)
			(layer "F.SilkS")
		)
		(fp_line
			(start -0.67945 0.3048)
			(end -0.67945 -0.305054)
			(stroke
				(width 0.1)
				(type default)
			)
			(layer "F.Fab")
		)
		(fp_line
			(start -0.12065 0.3048)
			(end -0.67945 0.3048)
			(stroke
				(width 0.1)
				(type default)
			)
			(layer "F.Fab")
		)
		(fp_line
			(start 0.120396 0.3048)
			(end 0.120396 0.2794)
			(stroke
				(width 0.1)
				(type default)
			)
			(layer "F.Fab")
		)
		(fp_line
			(start 0.67945 0.3048)
			(end 0.120396 0.3048)
			(stroke
				(width 0.1)
				(type default)
			)
			(layer "F.Fab")
		)
		(fp_line
			(start -0.12065 0.2794)
			(end -0.12065 0.3048)
			(stroke
				(width 0.1)
				(type default)
			)
			(layer "F.Fab")
		)
		(fp_line
			(start 0.120396 0.2794)
			(end -0.12065 0.2794)
			(stroke
				(width 0.1)
				(type default)
			)
			(layer "F.Fab")
		)
		(fp_line
			(start -0.12065 -0.2794)
			(end 0.12065 -0.2794)
			(stroke
				(width 0.1)
				(type default)
			)
			(layer "F.Fab")
		)
		(fp_line
			(start 0.12065 -0.2794)
			(end 0.12065 -0.3048)
			(stroke
				(width 0.1)
				(type default)
			)
			(layer "F.Fab")
		)
		(fp_line
			(start 0.12065 -0.3048)
			(end 0.67945 -0.3048)
			(stroke
				(width 0.1)
				(type default)
			)
			(layer "F.Fab")
		)
		(fp_line
			(start 0.67945 -0.3048)
			(end 0.67945 0.3048)
			(stroke
				(width 0.1)
				(type default)
			)
			(layer "F.Fab")
		)
		(fp_line
			(start -0.67945 -0.305054)
			(end -0.12065 -0.305054)
			(stroke
				(width 0.1)
				(type default)
			)
			(layer "F.Fab")
		)
		(fp_line
			(start -0.12065 -0.305054)
			(end -0.12065 -0.2794)
			(stroke
				(width 0.1)
				(type default)
			)
			(layer "F.Fab")
		)
		(pad "1" smd circle
			(at -0.40005 0 270)
			(size 0 0)
			(layers "F.Cu" "F.Mask" "F.Paste")
			(net "P5V_AUX")
		)
		(pad "2" smd circle
			(at 0.40005 0 270)
			(size 0 0)
			(layers "F.Cu" "F.Mask" "F.Paste")
			(net "GND")
		)
	)
)
